(kicad_pcb
	(version 20241229)
	(generator "pcbnew")
	(generator_version "9.0")
	(general
		(thickness 1.6)
		(legacy_teardrops no)
	)
	(paper "A4")
	(title_block
		(title "environment-sensor")
		(comment 1 "footprints 37-41 of 109")
	)
	(layers
		(0 "F.Cu" signal)
		(4 "In1.Cu" signal)
		(6 "In2.Cu" signal)
		(2 "B.Cu" signal)
		(9 "F.Adhes" user "F.Adhesive")
		(11 "B.Adhes" user "B.Adhesive")
		(13 "F.Paste" user)
		(15 "B.Paste" user)
		(5 "F.SilkS" user "F.Silkscreen")
		(7 "B.SilkS" user "B.Silkscreen")
		(1 "F.Mask" user)
		(3 "B.Mask" user)
		(17 "Dwgs.User" user "User.Drawings")
		(19 "Cmts.User" user "User.Comments")
		(21 "Eco1.User" user "User.Eco1")
		(23 "Eco2.User" user "User.Eco2")
		(25 "Edge.Cuts" user)
		(27 "Margin" user)
		(31 "F.CrtYd" user "F.Courtyard")
		(29 "B.CrtYd" user "B.Courtyard")
		(35 "F.Fab" user)
		(33 "B.Fab" user)
	)
	(footprint "antmicro-footprints:R_0402_1005Metric"
		(layer "F.Cu")
		(at 186.25 138.4 90)
		(descr "Resistor SMD 0402")
		(tags "resistor SMD 0402")
		(property "Reference" "R13"
			(at 20.346 -1.4685 270)
			(layer "B.SilkS")
			(effects
				(font
					(size 0.7 0.7)
					(thickness 0.15)
				)
				(justify left bottom mirror)
			)
		)
		(property "Value" "R_0R_0402"
			(at 0 1.4 90)
			(layer "F.Fab")
			(effects
				(font
					(size 0.7 0.7)
					(thickness 0.15)
				)
				(justify left bottom)
			)
		)
		(property "Description" "SMD Chip Resistor, Jumper, 0 ohm, 100 mW, 0402 [1005 Metric], Thick Film, General Purpose"
			(at 0 0 90)
			(layer "F.Fab")
			(hide yes)
			(effects
				(font
					(size 1.27 1.27)
					(thickness 0.15)
				)
			)
		)
		(property "Author" "Antmicro"
			(at 324.65 -47.85 0)
			(layer "F.Fab")
			(hide yes)
			(effects
				(font
					(size 1 1)
					(thickness 0.15)
				)
			)
		)
		(property "Current" "1A"
			(at 324.65 -47.85 0)
			(layer "F.Fab")
			(hide yes)
			(effects
				(font
					(size 1 1)
					(thickness 0.15)
				)
			)
		)
		(property "License" "Apache-2.0"
			(at 324.65 -47.85 0)
			(layer "F.Fab")
			(hide yes)
			(effects
				(font
					(size 1 1)
					(thickness 0.15)
				)
			)
		)
		(property "MPN" "ERJ2GE0R00X"
			(at 324.65 -47.85 0)
			(layer "F.Fab")
			(hide yes)
			(effects
				(font
					(size 1 1)
					(thickness 0.15)
				)
			)
		)
		(property "Manufacturer" "Panasonic"
			(at 324.65 -47.85 0)
			(layer "F.Fab")
			(hide yes)
			(effects
				(font
					(size 1 1)
					(thickness 0.15)
				)
			)
		)
		(property "Public" "False"
			(at 324.65 -47.85 0)
			(layer "F.Fab")
			(hide yes)
			(effects
				(font
					(size 1 1)
					(thickness 0.15)
				)
			)
		)
		(property "Tolerance" ""
			(at 324.65 -47.85 0)
			(layer "F.Fab")
			(hide yes)
			(effects
				(font
					(size 1 1)
					(thickness 0.15)
				)
			)
		)
		(property "Val" "0R"
			(at 324.65 -47.85 0)
			(layer "F.Fab")
			(hide yes)
			(effects
				(font
					(size 1 1)
					(thickness 0.15)
				)
			)
		)
		(sheetfile "environment-sensor.kicad_sch")
		(attr smd)
		(fp_rect
			(start -0.925 -0.47)
			(end 0.925 0.47)
			(stroke
				(width 0.05)
				(type default)
			)
			(fill no)
			(layer "F.CrtYd")
		)
		(fp_rect
			(start -0.5 -0.25)
			(end 0.5 0.25)
			(stroke
				(width 0.15)
				(type solid)
			)
			(fill no)
			(layer "F.Fab")
		)
		(pad "1" smd roundrect
			(at -0.48 0 90)
			(size 0.59 0.64)
			(layers "F.Cu" "F.Mask" "F.Paste")
			(roundrect_rratio 0.25)
			(net 44 "Net-(U1-TXD)")
			(pintype "passive")
		)
		(pad "2" smd roundrect
			(at 0.48 0 90)
			(size 0.59 0.64)
			(layers "F.Cu" "F.Mask" "F.Paste")
			(roundrect_rratio 0.25)
			(net 16 "LPUART_1_STM_RX")
			(pintype "passive")
		)
	)
	(footprint "antmicro-footprints:TP_SMD_1mm"
		(layer "F.Cu")
		(at 176.2 132.65)
		(property "Reference" "TP9"
			(at 0 -0.731898 0)
			(layer "F.SilkS")
			(hide yes)
			(effects
				(font
					(size 0.7 0.7)
					(thickness 0.15)
				)
				(justify left bottom)
			)
		)
		(property "Value" "TP_1mm_SMD"
			(at 0 1.4 0)
			(layer "F.Fab")
			(effects
				(font
					(size 0.7 0.7)
					(thickness 0.15)
				)
				(justify left bottom)
			)
		)
		(property "Description" "Test point 1mm SMD"
			(at 0 0 0)
			(layer "F.Fab")
			(hide yes)
			(effects
				(font
					(size 1.27 1.27)
					(thickness 0.15)
				)
			)
		)
		(property "Author" "Antmicro"
			(at 0 0 0)
			(layer "F.Fab")
			(hide yes)
			(effects
				(font
					(size 1 1)
					(thickness 0.15)
				)
			)
		)
		(property "License" "Apache-2.0"
			(at 0 0 0)
			(layer "F.Fab")
			(hide yes)
			(effects
				(font
					(size 1 1)
					(thickness 0.15)
				)
			)
		)
		(property "MPN" ""
			(at 0 0 0)
			(layer "F.Fab")
			(hide yes)
			(effects
				(font
					(size 1 1)
					(thickness 0.15)
				)
			)
		)
		(property "Manufacturer" ""
			(at 0 0 0)
			(layer "F.Fab")
			(hide yes)
			(effects
				(font
					(size 1 1)
					(thickness 0.15)
				)
			)
		)
		(property "Public" "False"
			(at 0 0 0)
			(layer "F.Fab")
			(hide yes)
			(effects
				(font
					(size 1 1)
					(thickness 0.15)
				)
			)
		)
		(sheetfile "environment-sensor.kicad_sch")
		(attr exclude_from_pos_files)
		(pad "1" smd circle
			(at 0 0)
			(size 1 1)
			(layers "F.Cu" "F.Mask")
			(net 2 "+3V3")
			(pinfunction "1")
			(pintype "passive")
		)
	)
	(footprint "antmicro-footprints:SOP-8_3.9x5.05mm_P1.27mm"
		(layer "F.Cu")
		(at 187.804 120.997 -90)
		(property "Reference" "U4"
			(at 3.353 3.804 0)
			(unlocked yes)
			(layer "F.SilkS")
			(effects
				(font
					(size 0.7 0.7)
					(thickness 0.15)
				)
				(justify left bottom)
			)
		)
		(property "Value" "MB85RC1MTPNF-G"
			(at -2.641 6.368 270)
			(unlocked yes)
			(layer "F.Fab")
			(effects
				(font
					(size 0.7 0.7)
					(thickness 0.15)
				)
				(justify left bottom)
			)
		)
		(property "Description" "FRAM (Ferroelectric RAM) Memory IC 1Mbit I²C 3.4 MHz 130 ns 8-SOP"
			(at 0 0 270)
			(layer "F.Fab")
			(hide yes)
			(effects
				(font
					(size 1.27 1.27)
					(thickness 0.15)
				)
			)
		)
		(property "Author" "Antmicro"
			(at 66.807 308.801 0)
			(layer "F.Fab")
			(hide yes)
			(effects
				(font
					(size 1 1)
					(thickness 0.15)
				)
			)
		)
		(property "License" "Apache-2.0"
			(at 66.807 308.801 0)
			(layer "F.Fab")
			(hide yes)
			(effects
				(font
					(size 1 1)
					(thickness 0.15)
				)
			)
		)
		(property "MPN" "MB85RC1MTPNF-G-JNERE1"
			(at 66.807 308.801 0)
			(layer "F.Fab")
			(hide yes)
			(effects
				(font
					(size 1 1)
					(thickness 0.15)
				)
			)
		)
		(property "Manufacturer" "Fujitsu"
			(at 66.807 308.801 0)
			(layer "F.Fab")
			(hide yes)
			(effects
				(font
					(size 1 1)
					(thickness 0.15)
				)
			)
		)
		(sheetfile "environment-sensor.kicad_sch")
		(attr smd)
		(fp_line
			(start 2.289 2.12)
			(end 2.588 2.12)
			(stroke
				(width 0.15)
				(type solid)
			)
			(layer "F.SilkS")
		)
		(fp_line
			(start 2.588 2.12)
			(end 2.588 1.82)
			(stroke
				(width 0.15)
				(type solid)
			)
			(layer "F.SilkS")
		)
		(fp_line
			(start -2.311 1.912)
			(end -2.311 2.717)
			(stroke
				(width 0.15)
				(type solid)
			)
			(layer "F.SilkS")
		)
		(fp_line
			(start -2.609 1.62)
			(end -2.311 1.912)
			(stroke
				(width 0.15)
				(type solid)
			)
			(layer "F.SilkS")
		)
		(fp_line
			(start -2.609 1.217)
			(end -2.609 1.62)
			(stroke
				(width 0.15)
				(type solid)
			)
			(layer "F.SilkS")
		)
		(fp_line
			(start -2.609 -2.081)
			(end -2.609 -1.782)
			(stroke
				(width 0.15)
				(type solid)
			)
			(layer "F.SilkS")
		)
		(fp_line
			(start -2.311 -2.081)
			(end -2.609 -2.081)
			(stroke
				(width 0.15)
				(type solid)
			)
			(layer "F.SilkS")
		)
		(fp_line
			(start 2.289 -2.081)
			(end 2.588 -2.081)
			(stroke
				(width 0.15)
				(type solid)
			)
			(layer "F.SilkS")
		)
		(fp_line
			(start 2.588 -2.081)
			(end 2.588 -1.782)
			(stroke
				(width 0.15)
				(type solid)
			)
			(layer "F.SilkS")
		)
		(fp_circle
			(center -2.54 3.81)
			(end -2.49 3.81)
			(stroke
				(width 0.15)
				(type solid)
			)
			(fill yes)
			(layer "F.SilkS")
		)
		(fp_rect
			(start -2.79 -3.75)
			(end 2.76 3.79)
			(stroke
				(width 0.05)
				(type solid)
			)
			(fill no)
			(layer "F.CrtYd")
		)
		(fp_line
			(start -2.058 1.969)
			(end 2.439 1.969)
			(stroke
				(width 0.15)
				(type solid)
			)
			(layer "F.Fab")
		)
		(fp_line
			(start -2.46 1.568)
			(end -2.058 1.969)
			(stroke
				(width 0.15)
				(type solid)
			)
			(layer "F.Fab")
		)
		(fp_line
			(start -2.46 1.568)
			(end -2.46 -1.93)
			(stroke
				(width 0.15)
				(type solid)
			)
			(layer "F.Fab")
		)
		(fp_line
			(start -2.46 -1.93)
			(end 2.439 -1.93)
			(stroke
				(width 0.15)
				(type solid)
			)
			(layer "F.Fab")
		)
		(fp_line
			(start 2.439 -1.93)
			(end 2.439 1.969)
			(stroke
				(width 0.15)
				(type solid)
			)
			(layer "F.Fab")
		)
		(pad "1" smd rect
			(at -1.915 2.467 270)
			(size 0.6 2)
			(layers "F.Cu" "F.Mask" "F.Paste")
			(net 85 "unconnected-(U4-NC-Pad1)")
			(pinfunction "NC")
			(pintype "no_connect")
		)
		(pad "2" smd rect
			(at -0.652 2.467 270)
			(size 0.6 2)
			(layers "F.Cu" "F.Mask" "F.Paste")
			(net 51 "Net-(U4-A1)")
			(pinfunction "A1")
			(pintype "input")
		)
		(pad "3" smd rect
			(at 0.618 2.467 270)
			(size 0.6 2)
			(layers "F.Cu" "F.Mask" "F.Paste")
			(net 52 "Net-(U4-A2)")
			(pinfunction "A2")
			(pintype "input")
		)
		(pad "4" smd rect
			(at 1.89 2.467 270)
			(size 0.6 2)
			(layers "F.Cu" "F.Mask" "F.Paste")
			(net 1 "GND")
			(pinfunction "VSS")
			(pintype "power_in")
		)
		(pad "5" smd rect
			(at 1.89 -2.431 270)
			(size 0.6 2)
			(layers "F.Cu" "F.Mask" "F.Paste")
			(net 9 "I2C_1_SDA")
			(pinfunction "SDA")
			(pintype "bidirectional")
		)
		(pad "6" smd rect
			(at 0.618 -2.431 270)
			(size 0.6 2)
			(layers "F.Cu" "F.Mask" "F.Paste")
			(net 8 "I2C_1_SCL")
			(pinfunction "SCL")
			(pintype "input")
		)
		(pad "7" smd rect
			(at -0.652 -2.431 270)
			(size 0.6 2)
			(layers "F.Cu" "F.Mask" "F.Paste")
			(net 15 "/FRAM_WP")
			(pinfunction "WP")
			(pintype "input")
		)
		(pad "8" smd rect
			(at -1.915 -2.431 270)
			(size 0.6 2)
			(layers "F.Cu" "F.Mask" "F.Paste")
			(net 2 "+3V3")
			(pinfunction "VDD")
			(pintype "power_in")
		)
	)
	(footprint "antmicro-footprints:SOT-23-3"
		(layer "F.Cu")
		(at 172.55 133.5 180)
		(property "Reference" "U2"
			(at 1.35 1.3 90)
			(layer "F.SilkS")
			(effects
				(font
					(size 0.65 0.65)
					(thickness 0.15)
				)
			)
		)
		(property "Value" "AP7370-33SA-7"
			(at 0.025 3.25 0)
			(layer "F.Fab")
			(effects
				(font
					(size 1 1)
					(thickness 0.15)
				)
			)
		)
		(property "Description" "Voltage regulator"
			(at 0 0 180)
			(layer "F.Fab")
			(hide yes)
			(effects
				(font
					(size 1.27 1.27)
					(thickness 0.15)
				)
			)
		)
		(property "Author" "Antmicro"
			(at 345.1 267 0)
			(layer "F.Fab")
			(hide yes)
			(effects
				(font
					(size 1 1)
					(thickness 0.15)
				)
			)
		)
		(property "License" "Apache-2.0"
			(at 345.1 267 0)
			(layer "F.Fab")
			(hide yes)
			(effects
				(font
					(size 1 1)
					(thickness 0.15)
				)
			)
		)
		(property "MPN" "AP7370-33SA-7"
			(at 345.1 267 0)
			(layer "F.Fab")
			(hide yes)
			(effects
				(font
					(size 1 1)
					(thickness 0.15)
				)
			)
		)
		(property "Manufacturer" "Diodes Incorporated"
			(at 345.1 267 0)
			(layer "F.Fab")
			(hide yes)
			(effects
				(font
					(size 1 1)
					(thickness 0.15)
				)
			)
		)
		(sheetfile "environment-sensor.kicad_sch")
		(attr smd)
		(fp_line
			(start 0.7 1.5)
			(end -0.7 1.5)
			(stroke
				(width 0.15)
				(type solid)
			)
			(layer "F.SilkS")
		)
		(fp_line
			(start 0.7 0.4)
			(end 0.7 1.5)
			(stroke
				(width 0.15)
				(type solid)
			)
			(layer "F.SilkS")
		)
		(fp_line
			(start 0.7 -0.4)
			(end 0.7 -1.5)
			(stroke
				(width 0.15)
				(type solid)
			)
			(layer "F.SilkS")
		)
		(fp_line
			(start 0.7 -1.5)
			(end -0.7 -1.5)
			(stroke
				(width 0.15)
				(type solid)
			)
			(layer "F.SilkS")
		)
		(fp_line
			(start -0.7 1.5)
			(end -0.7 1.35)
			(stroke
				(width 0.15)
				(type solid)
			)
			(layer "F.SilkS")
		)
		(fp_line
			(start -0.85 -1.35)
			(end -0.7 -1.5)
			(stroke
				(width 0.15)
				(type solid)
			)
			(layer "F.SilkS")
		)
		(fp_line
			(start -1.45 -1.35)
			(end -0.85 -1.35)
			(stroke
				(width 0.15)
				(type solid)
			)
			(layer "F.SilkS")
		)
		(fp_line
			(start 1.75 0.45)
			(end 0.85 0.45)
			(stroke
				(width 0.05)
				(type solid)
			)
			(layer "F.CrtYd")
		)
		(fp_line
			(start 1.75 -0.45)
			(end 1.75 0.45)
			(stroke
				(width 0.05)
				(type solid)
			)
			(layer "F.CrtYd")
		)
		(fp_line
			(start 0.85 1.65)
			(end -0.85 1.65)
			(stroke
				(width 0.05)
				(type solid)
			)
			(layer "F.CrtYd")
		)
		(fp_line
			(start 0.85 0.45)
			(end 0.85 1.65)
			(stroke
				(width 0.05)
				(type solid)
			)
			(layer "F.CrtYd")
		)
		(fp_line
			(start 0.825 -0.45)
			(end 1.75 -0.45)
			(stroke
				(width 0.05)
				(type solid)
			)
			(layer "F.CrtYd")
		)
		(fp_line
			(start 0.825 -1.6)
			(end 0.825 -0.45)
			(stroke
				(width 0.05)
				(type solid)
			)
			(layer "F.CrtYd")
		)
		(fp_line
			(start -0.85 1.65)
			(end -0.85 1.4)
			(stroke
				(width 0.05)
				(type solid)
			)
			(layer "F.CrtYd")
		)
		(fp_line
			(start -0.85 1.4)
			(end -1.75 1.4)
			(stroke
				(width 0.05)
				(type solid)
			)
			(layer "F.CrtYd")
		)
		(fp_line
			(start -0.85 0.5)
			(end -0.85 -0.5)
			(stroke
				(width 0.05)
				(type solid)
			)
			(layer "F.CrtYd")
		)
		(fp_line
			(start -0.85 -0.5)
			(end -1.75 -0.5)
			(stroke
				(width 0.05)
				(type solid)
			)
			(layer "F.CrtYd")
		)
		(fp_line
			(start -0.9 -1.4)
			(end -1.75 -1.4)
			(stroke
				(width 0.05)
				(type solid)
			)
			(layer "F.CrtYd")
		)
		(fp_line
			(start -0.9 -1.6)
			(end 0.825 -1.6)
			(stroke
				(width 0.05)
				(type solid)
			)
			(layer "F.CrtYd")
		)
		(fp_line
			(start -0.9 -1.6)
			(end -0.9 -1.4)
			(stroke
				(width 0.05)
				(type solid)
			)
			(layer "F.CrtYd")
		)
		(fp_line
			(start -1.75 1.4)
			(end -1.75 0.5)
			(stroke
				(width 0.05)
				(type solid)
			)
			(layer "F.CrtYd")
		)
		(fp_line
			(start -1.75 0.5)
			(end -0.85 0.5)
			(stroke
				(width 0.05)
				(type solid)
			)
			(layer "F.CrtYd")
		)
		(fp_line
			(start -1.75 -0.5)
			(end -1.75 -1.4)
			(stroke
				(width 0.05)
				(type solid)
			)
			(layer "F.CrtYd")
		)
		(fp_line
			(start 0.688 1.519)
			(end 0.688 -1.52)
			(stroke
				(width 0.15)
				(type solid)
			)
			(layer "F.Fab")
		)
		(fp_line
			(start -0.437 -1.526)
			(end 0.688 -1.526)
			(stroke
				(width 0.15)
				(type solid)
			)
			(layer "F.Fab")
		)
		(fp_line
			(start -0.437 -1.526)
			(end -0.712 -1.325)
			(stroke
				(width 0.15)
				(type solid)
			)
			(layer "F.Fab")
		)
		(fp_line
			(start -0.712 1.519)
			(end 0.688 1.519)
			(stroke
				(width 0.15)
				(type solid)
			)
			(layer "F.Fab")
		)
		(fp_line
			(start -0.712 -1.325)
			(end -0.712 1.523)
			(stroke
				(width 0.15)
				(type solid)
			)
			(layer "F.Fab")
		)
		(fp_text user "${REFERENCE}"
			(at -0.125 0.15 0)
			(layer "F.Fab")
			(effects
				(font
					(size 0.25 0.25)
					(thickness 0.05)
				)
			)
		)
		(pad "1" smd roundrect
			(at -1.1 -0.951 180)
			(size 1 0.6)
			(layers "F.Cu" "F.Mask" "F.Paste")
			(roundrect_rratio 0.15)
			(net 1 "GND")
			(pinfunction "GND")
			(pintype "power_in")
		)
		(pad "2" smd roundrect
			(at -1.1 0.949 180)
			(size 1 0.6)
			(layers "F.Cu" "F.Mask" "F.Paste")
			(roundrect_rratio 0.15)
			(net 2 "+3V3")
			(pinfunction "VOUT")
			(pintype "power_out")
		)
		(pad "3" smd roundrect
			(at 1.1 -0.0005 180)
			(size 1 0.6)
			(layers "F.Cu" "F.Mask" "F.Paste")
			(roundrect_rratio 0.15)
			(net 26 "+5V")
			(pinfunction "VIN")
			(pintype "power_in")
		)
	)
	(footprint "antmicro-footprints:C_0402_1005Metric"
		(layer "F.Cu")
		(at 182.925 135.9)
		(descr "Capacitor SMD 0402")
		(tags "capacitor SMD 0402")
		(property "Reference" "C21"
			(at 3.175 0.35 0)
			(layer "F.SilkS")
			(effects
				(font
					(size 0.7 0.7)
					(thickness 0.15)
				)
				(justify right bottom)
			)
		)
		(property "Value" "C_10p_0402"
			(at 0 1.4 0)
			(layer "F.Fab")
			(effects
				(font
					(size 0.7 0.7)
					(thickness 0.15)
				)
				(justify left bottom)
			)
		)
		(property "Description" "SMD Multilayer Ceramic Capacitor, 10 pF, 50 V, 0402 [1005 Metric], ± 2%, C0G / NP0, GCM"
			(at 0 0 0)
			(layer "F.Fab")
			(hide yes)
			(effects
				(font
					(size 1.27 1.27)
					(thickness 0.15)
				)
			)
		)
		(property "Author" "Antmicro"
			(at 0 0 0)
			(layer "F.Fab")
			(hide yes)
			(effects
				(font
					(size 1 1)
					(thickness 0.15)
				)
			)
		)
		(property "Dielectric" "C0G"
			(at 0 0 0)
			(layer "F.Fab")
			(hide yes)
			(effects
				(font
					(size 1 1)
					(thickness 0.15)
				)
			)
		)
		(property "License" "Apache-2.0"
			(at 0 0 0)
			(layer "F.Fab")
			(hide yes)
			(effects
				(font
					(size 1 1)
					(thickness 0.15)
				)
			)
		)
		(property "MPN" "GCM1555C1H100GA16D"
			(at 0 0 0)
			(layer "F.Fab")
			(hide yes)
			(effects
				(font
					(size 1 1)
					(thickness 0.15)
				)
			)
		)
		(property "Manufacturer" "Murata"
			(at 0 0 0)
			(layer "F.Fab")
			(hide yes)
			(effects
				(font
					(size 1 1)
					(thickness 0.15)
				)
			)
		)
		(property "Public" "False"
			(at 0 0 0)
			(layer "F.Fab")
			(hide yes)
			(effects
				(font
					(size 1 1)
					(thickness 0.15)
				)
			)
		)
		(property "Val" "10p"
			(at 0 0 0)
			(layer "F.Fab")
			(hide yes)
			(effects
				(font
					(size 1 1)
					(thickness 0.15)
				)
			)
		)
		(property "Voltage" "50V"
			(at 0 0 0)
			(layer "F.Fab")
			(hide yes)
			(effects
				(font
					(size 1 1)
					(thickness 0.15)
				)
			)
		)
		(sheetfile "environment-sensor.kicad_sch")
		(attr smd)
		(fp_rect
			(start -0.925 -0.47)
			(end 0.925 0.47)
			(stroke
				(width 0.05)
				(type default)
			)
			(fill no)
			(layer "F.CrtYd")
		)
		(fp_line
			(start -0.494 -0.25)
			(end 0.504 -0.25)
			(stroke
				(width 0.15)
				(type solid)
			)
			(layer "F.Fab")
		)
		(fp_line
			(start -0.494 0.248)
			(end -0.494 -0.25)
			(stroke
				(width 0.15)
				(type solid)
			)
			(layer "F.Fab")
		)
		(fp_line
			(start 0.504 -0.25)
			(end 0.504 0.248)
			(stroke
				(width 0.15)
				(type solid)
			)
			(layer "F.Fab")
		)
		(fp_line
			(start 0.504 0.248)
			(end -0.494 0.248)
			(stroke
				(width 0.15)
				(type solid)
			)
			(layer "F.Fab")
		)
		(pad "1" smd roundrect
			(at -0.48 0)
			(size 0.59 0.64)
			(layers "F.Cu" "F.Mask" "F.Paste")
			(roundrect_rratio 0.25)
			(net 1 "GND")
			(pintype "passive")
		)
		(pad "2" smd roundrect
			(at 0.48 0)
			(size 0.59 0.64)
			(layers "F.Cu" "F.Mask" "F.Paste")
			(roundrect_rratio 0.25)
			(net 31 "Net-(U3-PF1-OSC_OUT)")
			(pintype "passive")
		)
	)
)
